FILE_TYPE = CONNECTIVITY;
{Allegro Design Entry HDL 17.4-2019 S026 (4007227) 1/17/2022}
"PAGE_NUMBER" = 465;
0"NC";
1"P0V9_CPU1_RT_2D\g";
2"GND\g";
3"P0V9_CPU1_RT3_2A\g";
4"GND\g";
5"P1V8_CPU1_RT_1D\g";
6"GND\g";
7"P1V8_CPU1_RT3_1A\g";
8"GND\g";
9"GND\g";
10"GND\g";
11"P0V9_CPU1_RT3_2A_2D\g";
12"GND\g";
13"P1V8_CPU1_RT3_1A_1D\g";
%"Q_RES"
"1","(-7700,3525)","0","pure_quanta","I1";
;
LOCATION"R894"
SEC"1"
WATTAGE"1/16W"
PACK_TYPE"0402LF"
TOLERANCE"5%"
MATERIAL"EMPTY"
VALUE"0"
CDS_LIB"pure_quanta"
SEC_TYPE"0402LF"
PART_NUMBER"CS00002JB13";
"B"
$PN"2"7;
"A"
$PN"1"13;
%"Q_INDUCTOR"
"1","(-7775,4425)","0","pure_quanta","I11";
;
LOCATION"L9"
$SEC"1"
CDS_SEC"1"
VALUE"BLM21SN300SN1D/5A"
PACK_TYPE"SMLF"
MATERIAL"IND"
CDS_LIB"pure_quanta"
NEEDS_NO_SIZE"TRUE"
PART_NUMBER"CX300SN1000";
"1"
$PN"1"5;
"2"
$PN"2"7;
%"P1V0"
"1","(-7300,4625)","0","pure_quanta_power","I12";
;
HDL_POWER"P1V8_CPU1_RT3_1A"
CDS_LIB"pure_quanta_power";
"A"7;
%"P1V0"
"1","(-8150,5250)","0","pure_quanta_power","I13";
;
HDL_POWER"P1V8_CPU1_RT_1D"
CDS_LIB"pure_quanta_power";
"A"5;
%"Q_CAP"
"1","(-7200,4150)","0","pure_quanta","I14";
;
LOCATION"C433"
$SEC"1"
CDS_SEC"1"
TOLERANCE"20%"
MATERIAL"X6S"
PACK_TYPE"C0805"
VALUE"100UF"
VOLTAGE"4V"
CDS_LIB"pure_quanta"
PART_NUMBER"CH710KMEA01";
"B"
$PN"2"8;
"A"
$PN"1"7;
%"Q_CAP"
"1","(-6975,4150)","0","pure_quanta","I15";
;
LOCATION"C435"
$SEC"1"
CDS_SEC"1"
PACK_TYPE"C0402"
VALUE"22UF"
MATERIAL"X6S"
TOLERANCE"20%"
VOLTAGE"4V"
CDS_LIB"pure_quanta"
PART_NUMBER"CH622KMEB02";
"B"
$PN"2"8;
"A"
$PN"1"7;
%"Q_CAP"
"1","(-6775,4150)","0","pure_quanta","I16";
;
LOCATION"C437"
$SEC"1"
CDS_SEC"1"
VALUE"10UF"
VOLTAGE"6.3V"
TOLERANCE"20%"
PACK_TYPE"C0402"
MATERIAL"X6S"
CDS_LIB"pure_quanta"
PART_NUMBER"CH6101MEB01";
"B"
$PN"2"8;
"A"
$PN"1"7;
%"Q_CAP"
"1","(-7050,4975)","0","pure_quanta","I17";
;
LOCATION"C432"
$SEC"1"
CDS_SEC"1"
VALUE"100UF"
PACK_TYPE"C0805"
VOLTAGE"4V"
TOLERANCE"20%"
MATERIAL"X6S"
CDS_LIB"pure_quanta"
PART_NUMBER"CH710KMEA01";
"B"
$PN"2"6;
"A"
$PN"1"5;
%"Q_CAP"
"1","(-6800,4975)","0","pure_quanta","I18";
;
LOCATION"C434"
$SEC"1"
CDS_SEC"1"
TOLERANCE"20%"
VALUE"22UF"
PACK_TYPE"C0402"
VOLTAGE"4V"
MATERIAL"X6S"
CDS_LIB"pure_quanta"
PART_NUMBER"CH622KMEB02";
"B"
$PN"2"6;
"A"
$PN"1"5;
%"Q_CAP"
"1","(-6575,4150)","0","pure_quanta","I19";
;
LOCATION"C438"
$SEC"1"
CDS_SEC"1"
VALUE"4.7UF"
MATERIAL"X6S"
TOLERANCE"20%"
VOLTAGE"6.3V"
PACK_TYPE"0402"
CDS_LIB"pure_quanta"
PART_NUMBER"CH5471MEB01";
"B"
$PN"2"8;
"A"
$PN"1"7;
%"Q_RES"
"1","(-7700,3725)","0","pure_quanta","I2";
;
LOCATION"R893"
SEC"1"
WATTAGE"1/16W"
PACK_TYPE"0402LF"
MATERIAL"EMPTY"
VALUE"0"
TOLERANCE"5%"
SEC_TYPE"0402LF"
CDS_LIB"pure_quanta"
PART_NUMBER"CS00002JB13";
"B"
$PN"2"7;
"A"
$PN"1"13;
%"Q_CAP"
"1","(-6350,4150)","0","pure_quanta","I20";
;
LOCATION"C440"
$SEC"1"
CDS_SEC"1"
VALUE"1UF"
PACK_TYPE"0201"
MATERIAL"X6S"
VOLTAGE"4V"
TOLERANCE"20%"
CDS_LIB"pure_quanta"
PART_NUMBER"CH-10KMEE00";
"B"
$PN"2"8;
"A"
$PN"1"7;
%"Q_CAP"
"1","(-6550,4950)","0","pure_quanta","I21";
;
LOCATION"C436"
$SEC"1"
CDS_SEC"1"
PACK_TYPE"C0402"
VALUE"10UF"
VOLTAGE"6.3V"
MATERIAL"X6S"
TOLERANCE"20%"
CDS_LIB"pure_quanta"
PART_NUMBER"CH6101MEB01";
"B"
$PN"2"6;
"A"
$PN"1"5;
%"UNIVERSAL_GND"
"1","(-6375,4675)","0","pure_quanta_power","I22";
;
CDS_LIB"pure_quanta_power"
HDL_POWER"GND";
"A"6;
%"Q_CAP"
"1","(-6300,4950)","0","pure_quanta","I23";
;
LOCATION"C439"
$SEC"1"
CDS_SEC"1"
TOLERANCE"20%"
VOLTAGE"6.3V"
MATERIAL"X6S"
PACK_TYPE"0402"
VALUE"4.7UF"
CDS_LIB"pure_quanta"
PART_NUMBER"CH5471MEB01";
"B"
$PN"2"6;
"A"
$PN"1"5;
%"Q_CAP"
"1","(-6150,4150)","0","pure_quanta","I24";
;
LOCATION"C442"
$SEC"1"
CDS_SEC"1"
TOLERANCE"20%"
VALUE"1UF"
VOLTAGE"4V"
MATERIAL"X6S"
PACK_TYPE"0201"
CDS_LIB"pure_quanta"
PART_NUMBER"CH-10KMEE00";
"B"
$PN"2"8;
"A"
$PN"1"7;
%"Q_CAP"
"1","(-5925,4150)","0","pure_quanta","I25";
;
LOCATION"C443"
$SEC"1"
CDS_SEC"1"
VALUE"0.1UF"
VOLTAGE"10V"
MATERIAL"X7S"
TOLERANCE"10%"
PACK_TYPE"C0201"
CDS_LIB"pure_quanta"
PART_NUMBER"CH4102K6E00";
"B"
$PN"2"8;
"A"
$PN"1"7;
%"Q_CAP"
"1","(-5675,4150)","0","pure_quanta","I26";
;
LOCATION"C445"
$SEC"1"
CDS_SEC"1"
PACK_TYPE"C0201"
VALUE"0.1UF"
MATERIAL"X7S"
VOLTAGE"10V"
TOLERANCE"10%"
CDS_LIB"pure_quanta"
PART_NUMBER"CH4102K6E00";
"B"
$PN"2"8;
"A"
$PN"1"7;
%"Q_CAP"
"1","(-5425,4150)","0","pure_quanta","I27";
;
LOCATION"C446"
$SEC"1"
CDS_SEC"1"
PACK_TYPE"C0201"
MATERIAL"X7S"
VOLTAGE"10V"
VALUE"0.1UF"
TOLERANCE"10%"
CDS_LIB"pure_quanta"
PART_NUMBER"CH4102K6E00";
"B"
$PN"2"8;
"A"
$PN"1"7;
%"Q_CAP"
"1","(-5150,4150)","0","pure_quanta","I28";
;
LOCATION"C447"
$SEC"1"
CDS_SEC"1"
PACK_TYPE"C0201"
TOLERANCE"10%"
MATERIAL"X7S"
VOLTAGE"10V"
VALUE"0.1UF"
CDS_LIB"pure_quanta"
PART_NUMBER"CH4102K6E00";
"B"
$PN"2"8;
"A"
$PN"1"7;
%"VCC_CORE"
"1","(-4300,5925)","0","pure_quanta_power","I29";
;
HDL_POWER"P0V9_CPU1_RT_2D"
CDS_LIB"pure_quanta_power";
"A"1;
%"UNIVERSAL_GND"
"1","(-6500,2650)","0","pure_quanta_power","I3";
;
CDS_LIB"pure_quanta_power"
HDL_POWER"GND";
"A"10;
%"VCC_CORE"
"1","(-3150,1625)","0","pure_quanta_power","I30";
;
HDL_POWER"P0V9_CPU1_RT3_2A_2D"
CDS_LIB"pure_quanta_power";
"A"11;
%"UNIVERSAL_GND"
"1","(-2325,775)","0","pure_quanta_power","I31";
;
CDS_LIB"pure_quanta_power"
HDL_POWER"GND";
"A"12;
%"Q_CAP"
"1","(-2475,1100)","0","pure_quanta","I34";
;
LOCATION"C463"
$SEC"1"
CDS_SEC"1"
VALUE"0.1UF"
VOLTAGE"10V"
TOLERANCE"10%"
MATERIAL"X7S"
PACK_TYPE"C0201"
CDS_LIB"pure_quanta"
PART_NUMBER"CH4102K6E00";
"B"
$PN"2"12;
"A"
$PN"1"11;
%"Q_CAP"
"1","(-2225,1100)","0","pure_quanta","I35";
;
LOCATION"C464"
$SEC"1"
CDS_SEC"1"
VOLTAGE"10V"
TOLERANCE"10%"
VALUE"0.1UF"
PACK_TYPE"C0201"
MATERIAL"X7S"
CDS_LIB"pure_quanta"
PART_NUMBER"CH4102K6E00";
"B"
$PN"2"12;
"A"
$PN"1"11;
%"Q_RES"
"1","(-3925,2450)","0","pure_quanta","I36";
;
LOCATION"R900"
$SEC"1"
CDS_SEC"1"
PACK_TYPE"0603LF"
WATTAGE"1/4W"
MATERIAL"CHIP"
TOLERANCE"5%"
VALUE"0"
CDS_LIB"pure_quanta"
PART_NUMBER"CS00006J900";
"B"
$PN"2"3;
"A"
$PN"1"11;
%"Q_CAP"
"1","(-3200,2200)","0","pure_quanta","I37";
;
LOCATION"C495"
$SEC"1"
CDS_SEC"1"
VALUE"0.1UF"
PACK_TYPE"C0201"
MATERIAL"X7S"
VOLTAGE"10V"
TOLERANCE"10%"
CDS_LIB"pure_quanta"
PART_NUMBER"CH4102K6E00";
"B"
$PN"2"9;
"A"
$PN"1"3;
%"Q_CAP"
"1","(-3475,2900)","0","pure_quanta","I38";
;
LOCATION"C470"
$SEC"1"
CDS_SEC"1"
VALUE"1UF"
PACK_TYPE"0201"
MATERIAL"X6S"
VOLTAGE"4V"
TOLERANCE"20%"
CDS_LIB"pure_quanta"
PART_NUMBER"CH-10KMEE00";
"B"
$PN"2"4;
"A"
$PN"1"3;
%"Q_CAP"
"1","(-3250,2900)","0","pure_quanta","I39";
;
LOCATION"C459"
$SEC"1"
CDS_SEC"1"
VOLTAGE"4V"
VALUE"1UF"
PACK_TYPE"0201"
MATERIAL"X6S"
TOLERANCE"20%"
CDS_LIB"pure_quanta"
PART_NUMBER"CH-10KMEE00";
"B"
$PN"2"4;
"A"
$PN"1"3;
%"Q_CAP"
"1","(-6775,3075)","0","pure_quanta","I4";
;
LOCATION"C441"
$SEC"1"
CDS_SEC"1"
VALUE"1UF"
VOLTAGE"4V"
TOLERANCE"20%"
MATERIAL"X6S"
PACK_TYPE"0201"
CDS_LIB"pure_quanta"
PART_NUMBER"CH-10KMEE00";
"B"
$PN"2"10;
"A"
$PN"1"13;
%"Q_CAP"
"1","(-3475,3525)","0","pure_quanta","I40";
;
LOCATION"C480"
$SEC"1"
CDS_SEC"1"
VALUE"10UF"
VOLTAGE"6.3V"
MATERIAL"X6S"
TOLERANCE"20%"
PACK_TYPE"C0402"
CDS_LIB"pure_quanta"
PART_NUMBER"CH6101MEB01";
"B"
$PN"2"4;
"A"
$PN"1"3;
%"Q_CAP"
"1","(-3250,3525)","0","pure_quanta","I41";
;
LOCATION"C490"
$SEC"1"
CDS_SEC"1"
TOLERANCE"20%"
VOLTAGE"6.3V"
VALUE"10UF"
MATERIAL"X6S"
PACK_TYPE"C0402"
CDS_LIB"pure_quanta"
PART_NUMBER"CH6101MEB01";
"B"
$PN"2"4;
"A"
$PN"1"3;
%"Q_CAP"
"1","(-2900,2200)","0","pure_quanta","I42";
;
LOCATION"C500"
$SEC"1"
CDS_SEC"1"
VALUE"0.1UF"
VOLTAGE"10V"
PACK_TYPE"C0201"
MATERIAL"X7S"
TOLERANCE"10%"
CDS_LIB"pure_quanta"
PART_NUMBER"CH4102K6E00";
"B"
$PN"2"9;
"A"
$PN"1"3;
%"Q_CAP"
"1","(-2675,2200)","0","pure_quanta","I43";
;
LOCATION"C473"
$SEC"1"
CDS_SEC"1"
VALUE"0.1UF"
TOLERANCE"10%"
VOLTAGE"10V"
PACK_TYPE"C0201"
MATERIAL"X7S"
CDS_LIB"pure_quanta"
PART_NUMBER"CH4102K6E00";
"B"
$PN"2"9;
"A"
$PN"1"3;
%"Q_CAP"
"1","(-3000,2900)","0","pure_quanta","I44";
;
LOCATION"C448"
$SEC"1"
CDS_SEC"1"
VOLTAGE"4V"
VALUE"1UF"
TOLERANCE"20%"
PACK_TYPE"0201"
MATERIAL"X6S"
CDS_LIB"pure_quanta"
PART_NUMBER"CH-10KMEE00";
"B"
$PN"2"4;
"A"
$PN"1"3;
%"Q_CAP"
"1","(-2775,2900)","0","pure_quanta","I45";
;
LOCATION"C453"
$SEC"1"
CDS_SEC"1"
TOLERANCE"20%"
VALUE"1UF"
PACK_TYPE"0201"
MATERIAL"X6S"
VOLTAGE"4V"
CDS_LIB"pure_quanta"
PART_NUMBER"CH-10KMEE00";
"B"
$PN"2"4;
"A"
$PN"1"3;
%"Q_CAP"
"1","(-2425,2200)","0","pure_quanta","I46";
;
LOCATION"C477"
$SEC"1"
CDS_SEC"1"
VALUE"0.1UF"
VOLTAGE"10V"
TOLERANCE"10%"
MATERIAL"X7S"
PACK_TYPE"C0201"
CDS_LIB"pure_quanta"
PART_NUMBER"CH4102K6E00";
"B"
$PN"2"9;
"A"
$PN"1"3;
%"Q_CAP"
"1","(-2175,2200)","0","pure_quanta","I47";
;
LOCATION"C450"
$SEC"1"
CDS_SEC"1"
PACK_TYPE"C0201"
VALUE"0.1UF"
TOLERANCE"10%"
VOLTAGE"10V"
MATERIAL"X7S"
CDS_LIB"pure_quanta"
PART_NUMBER"CH4102K6E00";
"B"
$PN"2"9;
"A"
$PN"1"3;
%"Q_CAP"
"1","(-2525,2900)","0","pure_quanta","I48";
;
LOCATION"C485"
$SEC"1"
CDS_SEC"1"
VALUE"1UF"
MATERIAL"X6S"
VOLTAGE"4V"
TOLERANCE"20%"
PACK_TYPE"0201"
CDS_LIB"pure_quanta"
PART_NUMBER"CH-10KMEE00";
"B"
$PN"2"4;
"A"
$PN"1"3;
%"Q_CAP"
"1","(-2300,2875)","0","pure_quanta","I49";
;
LOCATION"C488"
$SEC"1"
CDS_SEC"1"
VOLTAGE"4V"
MATERIAL"X6S"
VALUE"1UF"
TOLERANCE"20%"
PACK_TYPE"0201"
CDS_LIB"pure_quanta"
PART_NUMBER"CH-10KMEE00";
"B"
$PN"2"4;
"A"
$PN"1"3;
%"P1V0"
"1","(-6900,3450)","0","pure_quanta_power","I5";
;
HDL_POWER"P1V8_CPU1_RT3_1A_1D"
CDS_LIB"pure_quanta_power";
"A"13;
%"Q_CAP"
"1","(-3025,3525)","0","pure_quanta","I50";
;
LOCATION"C472"
$SEC"1"
CDS_SEC"1"
MATERIAL"X6S"
VOLTAGE"6.3V"
VALUE"4.7UF"
PACK_TYPE"0402"
TOLERANCE"20%"
CDS_LIB"pure_quanta"
PART_NUMBER"CH5471MEB01";
"B"
$PN"2"4;
"A"
$PN"1"3;
%"Q_CAP"
"1","(-2800,3525)","0","pure_quanta","I51";
;
LOCATION"C469"
$SEC"1"
CDS_SEC"1"
PACK_TYPE"0402"
VOLTAGE"6.3V"
TOLERANCE"20%"
VALUE"4.7UF"
MATERIAL"X6S"
CDS_LIB"pure_quanta"
PART_NUMBER"CH5471MEB01";
"B"
$PN"2"4;
"A"
$PN"1"3;
%"Q_CAP"
"1","(-2325,3525)","0","pure_quanta","I52";
;
LOCATION"C494"
$SEC"1"
CDS_SEC"1"
PACK_TYPE"0402"
VOLTAGE"6.3V"
MATERIAL"X6S"
TOLERANCE"20%"
VALUE"4.7UF"
CDS_LIB"pure_quanta"
PART_NUMBER"CH5471MEB01";
"B"
$PN"2"4;
"A"
$PN"1"3;
%"Q_CAP"
"1","(-2100,3525)","0","pure_quanta","I53";
;
LOCATION"C491"
$SEC"1"
CDS_SEC"1"
PACK_TYPE"0201"
MATERIAL"X6S"
VALUE"1UF"
TOLERANCE"20%"
VOLTAGE"4V"
CDS_LIB"pure_quanta"
PART_NUMBER"CH-10KMEE00";
"B"
$PN"2"4;
"A"
$PN"1"3;
%"Q_CAP"
"1","(-2075,2875)","0","pure_quanta","I54";
;
LOCATION"C492"
$SEC"1"
CDS_SEC"1"
MATERIAL"X6S"
VALUE"1UF"
PACK_TYPE"0201"
TOLERANCE"20%"
VOLTAGE"4V"
CDS_LIB"pure_quanta"
PART_NUMBER"CH-10KMEE00";
"B"
$PN"2"4;
"A"
$PN"1"3;
%"UNIVERSAL_GND"
"1","(-1375,1775)","0","pure_quanta_power","I55";
;
CDS_LIB"pure_quanta_power"
HDL_POWER"GND";
"A"9;
%"Q_CAP"
"1","(-1900,2200)","0","pure_quanta","I56";
;
LOCATION"C481"
$SEC"1"
CDS_SEC"1"
PACK_TYPE"C0201"
VALUE"0.1UF"
MATERIAL"X7S"
TOLERANCE"10%"
VOLTAGE"10V"
CDS_LIB"pure_quanta"
PART_NUMBER"CH4102K6E00";
"B"
$PN"2"9;
"A"
$PN"1"3;
%"Q_CAP"
"1","(-1625,2200)","0","pure_quanta","I57";
;
LOCATION"C457"
$SEC"1"
CDS_SEC"1"
MATERIAL"X7S"
VALUE"0.1UF"
PACK_TYPE"C0201"
TOLERANCE"10%"
VOLTAGE"10V"
CDS_LIB"pure_quanta"
PART_NUMBER"CH4102K6E00";
"B"
$PN"2"9;
"A"
$PN"1"3;
%"Q_CAP"
"1","(-6500,3050)","0","pure_quanta","I6";
;
LOCATION"C444"
$SEC"1"
CDS_SEC"1"
PACK_TYPE"C0201"
MATERIAL"X7S"
VOLTAGE"10V"
VALUE"0.1UF"
TOLERANCE"10%"
CDS_LIB"pure_quanta"
PART_NUMBER"CH4102K6E00";
"B"
$PN"2"10;
"A"
$PN"1"13;
%"Q_CAP"
"1","(-1650,3525)","0","pure_quanta","I60";
;
LOCATION"C497"
$SEC"1"
CDS_SEC"1"
MATERIAL"X6S"
PACK_TYPE"0201"
VALUE"1UF"
TOLERANCE"20%"
VOLTAGE"4V"
CDS_LIB"pure_quanta"
PART_NUMBER"CH-10KMEE00";
"B"
$PN"2"4;
"A"
$PN"1"3;
%"Q_CAP"
"1","(-1400,3525)","0","pure_quanta","I61";
;
LOCATION"C455"
$SEC"1"
CDS_SEC"1"
TOLERANCE"20%"
MATERIAL"X6S"
VALUE"1UF"
VOLTAGE"4V"
PACK_TYPE"0201"
CDS_LIB"pure_quanta"
PART_NUMBER"CH-10KMEE00";
"B"
$PN"2"4;
"A"
$PN"1"3;
%"UNIVERSAL_GND"
"1","(-875,2475)","0","pure_quanta_power","I62";
;
CDS_LIB"pure_quanta_power"
HDL_POWER"GND";
"A"4;
%"Q_INDUCTOR"
"1","(-3825,4425)","0","pure_quanta","I63";
;
LOCATION"L10"
$SEC"1"
CDS_SEC"1"
VALUE"100NH/16A"
PACK_TYPE"SMLF"
MATERIAL"IND"
NEEDS_NO_SIZE"TRUE"
CDS_LIB"pure_quanta"
PART_NUMBER"CV+10G0MZ04";
"1"
$PN"1"1;
"2"
$PN"2"3;
%"Q_CAP"
"1","(-3475,4150)","0","pure_quanta","I64";
;
LOCATION"C466"
$SEC"1"
CDS_SEC"1"
VALUE"100UF"
VOLTAGE"4V"
PACK_TYPE"C0805"
TOLERANCE"20%"
MATERIAL"X6S"
CDS_LIB"pure_quanta"
PART_NUMBER"CH710KMEA01";
"B"
$PN"2"4;
"A"
$PN"1"3;
%"Q_CAP"
"1","(-3250,4150)","0","pure_quanta","I65";
;
LOCATION"C471"
$SEC"1"
CDS_SEC"1"
TOLERANCE"20%"
VOLTAGE"4V"
PACK_TYPE"C0805"
VALUE"100UF"
MATERIAL"X6S"
CDS_LIB"pure_quanta"
PART_NUMBER"CH710KMEA01";
"B"
$PN"2"4;
"A"
$PN"1"3;
%"VCC_CORE"
"1","(-3475,4800)","0","pure_quanta_power","I66";
;
HDL_POWER"P0V9_CPU1_RT3_2A"
CDS_LIB"pure_quanta_power";
"A"3;
%"Q_CAP"
"1","(-3425,5425)","0","pure_quanta","I67";
;
LOCATION"C474"
$SEC"1"
CDS_SEC"1"
MATERIAL"X6S"
PACK_TYPE"C0805"
TOLERANCE"20%"
VOLTAGE"4V"
VALUE"100UF"
CDS_LIB"pure_quanta"
PART_NUMBER"CH710KMEA01";
"B"
$PN"2"2;
"A"
$PN"1"1;
%"Q_CAP"
"1","(-3150,5425)","0","pure_quanta","I68";
;
LOCATION"C478"
$SEC"1"
CDS_SEC"1"
TOLERANCE"20%"
PACK_TYPE"C0402"
MATERIAL"X6S"
VOLTAGE"4V"
VALUE"22UF"
CDS_LIB"pure_quanta"
PART_NUMBER"CH622KMEB02";
"B"
$PN"2"2;
"A"
$PN"1"1;
%"Q_CAP"
"1","(-3025,4150)","0","pure_quanta","I69";
;
LOCATION"C475"
$SEC"1"
CDS_SEC"1"
PACK_TYPE"C0805"
TOLERANCE"20%"
MATERIAL"X6S"
VOLTAGE"4V"
VALUE"100UF"
CDS_LIB"pure_quanta"
PART_NUMBER"CH710KMEA01";
"B"
$PN"2"4;
"A"
$PN"1"3;
%"UNIVERSAL_GND"
"1","(-6150,3825)","0","pure_quanta_power","I7";
;
CDS_LIB"pure_quanta_power"
HDL_POWER"GND";
"A"8;
%"Q_CAP"
"1","(-2550,4150)","0","pure_quanta","I70";
;
LOCATION"C501"
$SEC"1"
CDS_SEC"1"
MATERIAL"X6S"
PACK_TYPE"C0402"
VOLTAGE"4V"
TOLERANCE"20%"
VALUE"22UF"
CDS_LIB"pure_quanta"
PART_NUMBER"CH622KMEB02";
"B"
$PN"2"4;
"A"
$PN"1"3;
%"Q_CAP"
"1","(-2100,4150)","0","pure_quanta","I71";
;
LOCATION"C476"
$SEC"1"
CDS_SEC"1"
PACK_TYPE"C0402"
MATERIAL"X6S"
TOLERANCE"20%"
VOLTAGE"4V"
VALUE"22UF"
CDS_LIB"pure_quanta"
PART_NUMBER"CH622KMEB02";
"B"
$PN"2"4;
"A"
$PN"1"3;
%"Q_CAP"
"1","(-2825,5400)","0","pure_quanta","I72";
;
LOCATION"C489"
$SEC"1"
CDS_SEC"1"
VOLTAGE"6.3V"
TOLERANCE"20%"
VALUE"10UF"
MATERIAL"X6S"
PACK_TYPE"C0402"
CDS_LIB"pure_quanta"
PART_NUMBER"CH6101MEB01";
"B"
$PN"2"2;
"A"
$PN"1"1;
%"Q_CAP"
"1","(-2525,5400)","0","pure_quanta","I73";
;
LOCATION"C484"
$SEC"1"
CDS_SEC"1"
VOLTAGE"6.3V"
PACK_TYPE"0402"
MATERIAL"X6S"
TOLERANCE"20%"
VALUE"4.7UF"
CDS_LIB"pure_quanta"
PART_NUMBER"CH5471MEB01";
"B"
$PN"2"2;
"A"
$PN"1"1;
%"Q_CAP"
"1","(-2225,5400)","0","pure_quanta","I74";
;
LOCATION"C454"
$SEC"1"
CDS_SEC"1"
VALUE"1UF"
VOLTAGE"4V"
TOLERANCE"20%"
MATERIAL"X6S"
PACK_TYPE"0201"
CDS_LIB"pure_quanta"
PART_NUMBER"CH-10KMEE00";
"B"
$PN"2"2;
"A"
$PN"1"1;
%"Q_CAP"
"1","(-1875,4150)","0","pure_quanta","I75";
;
LOCATION"C487"
$SEC"1"
CDS_SEC"1"
PACK_TYPE"C0402"
MATERIAL"X6S"
TOLERANCE"20%"
VALUE"22UF"
VOLTAGE"4V"
CDS_LIB"pure_quanta"
PART_NUMBER"CH622KMEB02";
"B"
$PN"2"4;
"A"
$PN"1"3;
%"Q_CAP"
"1","(-1575,4150)","0","pure_quanta","I76";
;
LOCATION"C499"
$SEC"1"
CDS_SEC"1"
VALUE"10UF"
VOLTAGE"6.3V"
TOLERANCE"20%"
MATERIAL"X6S"
PACK_TYPE"C0402"
CDS_LIB"pure_quanta"
PART_NUMBER"CH6101MEB01";
"B"
$PN"2"4;
"A"
$PN"1"3;
%"Q_CAP"
"1","(-1275,4150)","0","pure_quanta","I77";
;
LOCATION"C482"
$SEC"1"
CDS_SEC"1"
PACK_TYPE"C0402"
MATERIAL"X6S"
TOLERANCE"20%"
VALUE"10UF"
VOLTAGE"6.3V"
CDS_LIB"pure_quanta"
PART_NUMBER"CH6101MEB01";
"B"
$PN"2"4;
"A"
$PN"1"3;
%"Q_CAP"
"1","(-1925,5375)","0","pure_quanta","I78";
;
LOCATION"C449"
$SEC"1"
CDS_SEC"1"
VOLTAGE"10V"
VALUE"0.1UF"
PACK_TYPE"C0201"
MATERIAL"X7S"
TOLERANCE"10%"
CDS_LIB"pure_quanta"
PART_NUMBER"CH4102K6E00";
"B"
$PN"2"2;
"A"
$PN"1"1;
%"Q_CAP"
"1","(-1650,5375)","0","pure_quanta","I79";
;
LOCATION"C451"
$SEC"1"
CDS_SEC"1"
TOLERANCE"10%"
PACK_TYPE"C0201"
MATERIAL"X7S"
VOLTAGE"10V"
VALUE"0.1UF"
CDS_LIB"pure_quanta"
PART_NUMBER"CH4102K6E00";
"B"
$PN"2"2;
"A"
$PN"1"1;
%"Q_RES"
"2","(-4300,2725)","2","pure_quanta","I8";
;
LOCATION"R898"
$SEC"1"
CDS_SEC"1"
WATTAGE"1/4W"
MATERIAL"EMPTY"
PACK_TYPE"0603LF"
VALUE"0"
TOLERANCE"5%"
CDS_LIB"pure_quanta"
PART_NUMBER"CS00006J900";
"A"
$PN"1"1;
"B"
$PN"2"11;
%"Q_CAP"
"1","(-1400,5375)","0","pure_quanta","I80";
;
LOCATION"C493"
$SEC"1"
CDS_SEC"1"
PACK_TYPE"C0201"
MATERIAL"X7S"
TOLERANCE"10%"
VOLTAGE"10V"
VALUE"0.1UF"
CDS_LIB"pure_quanta"
PART_NUMBER"CH4102K6E00";
"B"
$PN"2"2;
"A"
$PN"1"1;
%"UNIVERSAL_GND"
"1","(-1200,4975)","0","pure_quanta_power","I81";
;
CDS_LIB"pure_quanta_power"
HDL_POWER"GND";
"A"2;
%"Q_CAP"
"1","(-1125,5375)","0","pure_quanta","I82";
;
LOCATION"C458"
$SEC"1"
CDS_SEC"1"
PACK_TYPE"C0201"
MATERIAL"X7S"
TOLERANCE"10%"
VOLTAGE"10V"
VALUE"0.1UF"
CDS_LIB"pure_quanta"
PART_NUMBER"CH4102K6E00";
"B"
$PN"2"2;
"A"
$PN"1"1;
%"Q_CAP"
"1","(-1375,2200)","0","pure_quanta","I83";
;
LOCATION"C462"
$SEC"1"
CDS_SEC"1"
PACK_TYPE"C0201"
VALUE"0.1UF"
MATERIAL"X7S"
VOLTAGE"10V"
TOLERANCE"10%"
CDS_LIB"pure_quanta"
PART_NUMBER"CH4102K6E00";
"B"
$PN"2"9;
"A"
$PN"1"3;
%"Q_CAP"
"1","(-1875,3525)","0","pure_quanta","I84";
;
LOCATION"C452"
$SEC"1"
CDS_SEC"1"
PACK_TYPE"0201"
VALUE"1UF"
TOLERANCE"20%"
MATERIAL"X6S"
VOLTAGE"4V"
CDS_LIB"pure_quanta"
PART_NUMBER"CH-10KMEE00";
"B"
$PN"2"4;
"A"
$PN"1"3;
%"Q_CAP"
"1","(-2325,4150)","0","pure_quanta","I85";
;
LOCATION"C486"
$SEC"1"
CDS_SEC"1"
TOLERANCE"20%"
MATERIAL"X6S"
VOLTAGE"4V"
VALUE"22UF"
PACK_TYPE"C0402"
CDS_LIB"pure_quanta"
PART_NUMBER"CH622KMEB02";
"B"
$PN"2"4;
"A"
$PN"1"3;
%"Q_CAP"
"1","(-2550,3525)","0","pure_quanta","I86";
;
LOCATION"C483"
$SEC"1"
CDS_SEC"1"
MATERIAL"X6S"
TOLERANCE"20%"
VOLTAGE"6.3V"
PACK_TYPE"0402"
VALUE"4.7UF"
CDS_LIB"pure_quanta"
PART_NUMBER"CH5471MEB01";
"B"
$PN"2"4;
"A"
$PN"1"3;
%"Q_CAP"
"1","(-2800,4150)","0","pure_quanta","I87";
;
LOCATION"C479"
$SEC"1"
CDS_SEC"1"
PACK_TYPE"C0805"
TOLERANCE"20%"
VALUE"100UF"
VOLTAGE"4V"
MATERIAL"X6S"
CDS_LIB"pure_quanta"
PART_NUMBER"CH710KMEA01";
"B"
$PN"2"4;
"A"
$PN"1"3;
%"Q_INDUCTOR"
"1","(-8225,4075)","3","pure_quanta","I88";
;
LOCATION"L33"
$SEC"1"
CDS_SEC"1"
MATERIAL"IND"
VALUE"BLM15PD121SN1D/1300MA"
PACK_TYPE"SMLF"
NEEDS_NO_SIZE"TRUE"
CDS_LIB"pure_quanta"
PART_NUMBER"CX5PD121000";
"1"
$PN"1"5;
"2"
$PN"2"13;
%"Q_RES"
"2","(-8100,4050)","0","pure_quanta","I89";
;
LOCATION"R897"
$SEC"1"
CDS_SEC"1"
VALUE"0"
WATTAGE"1/16W"
TOLERANCE"5%"
PACK_TYPE"0402LF"
MATERIAL"EMPTY"
CDS_LIB"pure_quanta"
PART_NUMBER"CS00002JB13";
"A"
$PN"1"5;
"B"
$PN"2"13;
%"Q_CAP"
"1","(-3025,1100)","0","pure_quanta","I90";
;
LOCATION"C456"
$SEC"1"
CDS_SEC"1"
PACK_TYPE"0201"
MATERIAL"X6S"
TOLERANCE"20%"
VALUE"1UF"
VOLTAGE"4V"
CDS_LIB"pure_quanta"
PART_NUMBER"CH-10KMEE00";
"B"
$PN"2"12;
"A"
$PN"1"11;
%"Q_CAP"
"1","(-2775,1100)","0","pure_quanta","I91";
;
LOCATION"C460"
$SEC"1"
CDS_SEC"1"
VALUE"1UF"
TOLERANCE"20%"
MATERIAL"X6S"
PACK_TYPE"0201"
VOLTAGE"4V"
CDS_LIB"pure_quanta"
PART_NUMBER"CH-10KMEE00";
"B"
$PN"2"12;
"A"
$PN"1"11;
%"Q_CAP"
"1","(-1850,2875)","0","pure_quanta","I92";
;
LOCATION"C496"
$SEC"1"
CDS_SEC"1"
PACK_TYPE"C0201"
TOLERANCE"10%"
VALUE"0.1UF"
VOLTAGE"10V"
MATERIAL"X7S"
CDS_LIB"pure_quanta"
PART_NUMBER"CH4102K6E00";
"B"
$PN"2"4;
"A"
$PN"1"3;
%"Q_CAP"
"1","(-1600,2875)","0","pure_quanta","I93";
;
LOCATION"C498"
$SEC"1"
CDS_SEC"1"
VALUE"0.1UF"
VOLTAGE"10V"
TOLERANCE"10%"
PACK_TYPE"C0201"
MATERIAL"X7S"
CDS_LIB"pure_quanta"
PART_NUMBER"CH4102K6E00";
"B"
$PN"2"4;
"A"
$PN"1"3;
%"Q_CAPP"
"1","(-1075,2225)","0","pure_quanta","I94";
;
LOCATION"C7029"
$SEC"1"
CDS_SEC"1"
PACK_TYPE"SMLF"
MATERIAL"SPCAP"
VOLTAGE"2.5V"
VALUE"470UF"
TOLERANCE"20%"
CDS_LIB"pure_quanta"
PART_NUMBER"CH747LM8818";
"A"
$PN"1"3;
"B"
$PN"2"9;
%"Q_CAPP"
"1","(-775,2225)","0","pure_quanta","I95";
;
LOCATION"C7030"
$SEC"1"
CDS_SEC"1"
PACK_TYPE"SMLF"
VALUE"470UF"
MATERIAL"SPCAP"
VOLTAGE"2.5V"
TOLERANCE"20%"
CDS_LIB"pure_quanta"
PART_NUMBER"CH747LM8818";
"A"
$PN"1"3;
"B"
$PN"2"9;
%"Q_CAP"
"1","(-475,2225)","0","pure_quanta","I96";
;
LOCATION"C7031"
$SEC"1"
CDS_SEC"1"
VALUE"100UF"
VOLTAGE"4V"
PACK_TYPE"C0805"
MATERIAL"X6S"
TOLERANCE"20%"
CDS_LIB"pure_quanta"
PART_NUMBER"CH710KMEA01";
"B"
$PN"2"9;
"A"
$PN"1"3;
END.
